(kicad_pcb
	(version 20241229)
	(generator "pcbnew")
	(generator_version "9.0")
	(general
		(thickness 1.6296)
		(legacy_teardrops no)
	)
	(paper "A3")
	(title_block
		(title "Thunderbolt to 10GbE adapter")
		(date "2026-04-21")
		(rev "1.1.0")
		(company "Antmicro Ltd")
		(comment 1 "www.antmicro.com")
		(comment 9 "footprints 607-610 of 703")
	)
	(layers
		(0 "F.Cu" signal)
		(4 "In1.Cu" signal)
		(6 "In2.Cu" signal)
		(8 "In3.Cu" signal)
		(10 "In4.Cu" signal)
		(12 "In5.Cu" signal)
		(14 "In6.Cu" signal)
		(2 "B.Cu" signal)
		(9 "F.Adhes" user "F.Adhesive")
		(11 "B.Adhes" user "B.Adhesive")
		(13 "F.Paste" user)
		(15 "B.Paste" user)
		(5 "F.SilkS" user "F.Silkscreen")
		(7 "B.SilkS" user "B.Silkscreen")
		(1 "F.Mask" user)
		(3 "B.Mask" user)
		(17 "Dwgs.User" user "User.Drawings")
		(19 "Cmts.User" user "User.Comments")
		(21 "Eco1.User" user "User.Eco1")
		(23 "Eco2.User" user "User.Eco2")
		(25 "Edge.Cuts" user)
		(27 "Margin" user)
		(31 "F.CrtYd" user "F.Courtyard")
		(29 "B.CrtYd" user "B.Courtyard")
		(35 "F.Fab" user)
		(33 "B.Fab" user)
	)
	(footprint "antmicro-footprints:R_0402_1005Metric"
		(layer "B.Cu")
		(at 126.8 144.4 90)
		(descr "Resistor SMD 0402")
		(tags "resistor SMD 0402")
		(property "Reference" "R33"
			(at 1.15 2.45 270)
			(layer "B.SilkS")
			(effects
				(font
					(size 0.7 0.7)
					(thickness 0.15)
				)
				(justify left bottom mirror)
			)
		)
		(property "Value" "R_5k1_0402"
			(at -1.011843 -1.772047 270)
			(layer "B.Fab")
			(effects
				(font
					(size 0.7 0.7)
					(thickness 0.15)
				)
				(justify left bottom mirror)
			)
		)
		(property "Datasheet" "https://www.bourns.com/docs/product-datasheets/cr.pdf"
			(at 0 0 270)
			(layer "B.Fab")
			(hide yes)
			(effects
				(font
					(size 1.27 1.27)
					(thickness 0.15)
				)
				(justify mirror)
			)
		)
		(property "Description" "SMD Chip Resistor, 5.1 kohm, ± 1%, 63 mW, 0402 [1005 Metric], Thick Film, General Purpose"
			(at 0 0 270)
			(layer "B.Fab")
			(hide yes)
			(effects
				(font
					(size 1.27 1.27)
					(thickness 0.15)
				)
				(justify mirror)
			)
		)
		(property "MPN" "CR0402-FX-5101GLF"
			(at 0 0 90)
			(unlocked yes)
			(layer "B.Fab")
			(hide yes)
			(effects
				(font
					(size 1 1)
					(thickness 0.15)
				)
				(justify mirror)
			)
		)
		(property "Manufacturer" "Bourns"
			(at 0 0 90)
			(unlocked yes)
			(layer "B.Fab")
			(hide yes)
			(effects
				(font
					(size 1 1)
					(thickness 0.15)
				)
				(justify mirror)
			)
		)
		(property "License" "Apache-2.0"
			(at 0 0 90)
			(unlocked yes)
			(layer "B.Fab")
			(hide yes)
			(effects
				(font
					(size 1 1)
					(thickness 0.15)
				)
				(justify mirror)
			)
		)
		(property "Val" "5k1"
			(at 0 0 90)
			(unlocked yes)
			(layer "B.Fab")
			(hide yes)
			(effects
				(font
					(size 1 1)
					(thickness 0.15)
				)
				(justify mirror)
			)
		)
		(property "Tolerance" "1%"
			(at 0 0 90)
			(unlocked yes)
			(layer "B.Fab")
			(hide yes)
			(effects
				(font
					(size 1 1)
					(thickness 0.15)
				)
				(justify mirror)
			)
		)
		(property "Author" "Antmicro"
			(at 0 0 90)
			(unlocked yes)
			(layer "B.Fab")
			(hide yes)
			(effects
				(font
					(size 1 1)
					(thickness 0.15)
				)
				(justify mirror)
			)
		)
		(sheetname "/PD and TB DC-DC/")
		(sheetfile "PD_and_TB_DC_DC.kicad_sch")
		(attr smd)
		(fp_rect
			(start -0.925 0.47)
			(end 0.925 -0.47)
			(stroke
				(width 0.05)
				(type default)
			)
			(fill no)
			(layer "B.CrtYd")
		)
		(fp_rect
			(start -0.5 0.25)
			(end 0.5 -0.25)
			(stroke
				(width 0.15)
				(type solid)
			)
			(fill no)
			(layer "B.Fab")
		)
		(fp_text user "License: Apache-2.0"
			(at -0.95 -5.169 270)
			(layer "B.Fab")
			(effects
				(font
					(size 0.7 0.7)
					(thickness 0.15)
				)
				(justify left bottom mirror)
			)
		)
		(fp_text user "Author: Antmicro"
			(at -0.95 -4.169 270)
			(layer "B.Fab")
			(effects
				(font
					(size 0.7 0.7)
					(thickness 0.15)
				)
				(justify left bottom mirror)
			)
		)
		(fp_text user "${REFERENCE}"
			(at -0.95 -3.168 270)
			(layer "B.Fab")
			(effects
				(font
					(size 0.7 0.7)
					(thickness 0.15)
				)
				(justify left bottom mirror)
			)
		)
		(pad "1" smd roundrect
			(at -0.48 0 90)
			(size 0.59 0.64)
			(layers "B.Cu" "B.Mask" "B.Paste")
			(roundrect_rratio 0.25)
			(net 23 "GND")
			(pintype "passive")
		)
		(pad "2" smd roundrect
			(at 0.48 0 90)
			(size 0.59 0.64)
			(layers "B.Cu" "B.Mask" "B.Paste")
			(roundrect_rratio 0.25)
			(net 306 "/PD and TB DC-DC/USB3.CC1")
			(pintype "passive")
		)
	)
	(footprint "antmicro-footprints:FB_0603_1608Metric"
		(layer "B.Cu")
		(at 163.25 132)
		(property "Reference" "FB9"
			(at 4.5 -2.5 180)
			(layer "B.SilkS")
			(effects
				(font
					(size 0.7 0.7)
					(thickness 0.15)
				)
				(justify left bottom mirror)
			)
		)
		(property "Value" "FB_33Z_3A_Murata-BLM18PG_0603"
			(at 0 -1.5 180)
			(layer "B.Fab")
			(effects
				(font
					(size 0.7 0.7)
					(thickness 0.15)
				)
				(justify left bottom mirror)
			)
		)
		(property "Datasheet" "https://www.murata.com/products/productdata/8796737273886/QNFA9101.pdf?1649080818000"
			(at 0 0 180)
			(layer "B.Fab")
			(hide yes)
			(effects
				(font
					(size 1.27 1.27)
					(thickness 0.15)
				)
				(justify mirror)
			)
		)
		(property "Description" "Ferrite Bead, 0603 [1608 Metric], 33 ohm, 3 A, BLM18PG, 0.025 ohm, ± 25%, DC power line"
			(at 0 0 180)
			(layer "B.Fab")
			(hide yes)
			(effects
				(font
					(size 1.27 1.27)
					(thickness 0.15)
				)
				(justify mirror)
			)
		)
		(property "Val" "33Z/3A"
			(at 0 0 0)
			(unlocked yes)
			(layer "B.Fab")
			(hide yes)
			(effects
				(font
					(size 1 1)
					(thickness 0.15)
				)
				(justify mirror)
			)
		)
		(property "MPN" "BLM18PG330SH1D"
			(at 0 0 0)
			(unlocked yes)
			(layer "B.Fab")
			(hide yes)
			(effects
				(font
					(size 1 1)
					(thickness 0.15)
				)
				(justify mirror)
			)
		)
		(property "Manufacturer" "Murata"
			(at 0 0 0)
			(unlocked yes)
			(layer "B.Fab")
			(hide yes)
			(effects
				(font
					(size 1 1)
					(thickness 0.15)
				)
				(justify mirror)
			)
		)
		(property "Current" ""
			(at 0 0 0)
			(unlocked yes)
			(layer "B.Fab")
			(hide yes)
			(effects
				(font
					(size 1 1)
					(thickness 0.15)
				)
				(justify mirror)
			)
		)
		(property "Author" "Antmicro"
			(at 0 0 0)
			(unlocked yes)
			(layer "B.Fab")
			(hide yes)
			(effects
				(font
					(size 1 1)
					(thickness 0.15)
				)
				(justify mirror)
			)
		)
		(property "License" "Apache-2.0"
			(at 0 0 0)
			(unlocked yes)
			(layer "B.Fab")
			(hide yes)
			(effects
				(font
					(size 1 1)
					(thickness 0.15)
				)
				(justify mirror)
			)
		)
		(sheetname "/2xRJ45/")
		(sheetfile "2xrj45.kicad_sch")
		(attr smd)
		(fp_line
			(start -0.15 -0.4)
			(end 0.15 -0.4)
			(stroke
				(width 0.15)
				(type solid)
			)
			(layer "B.SilkS")
		)
		(fp_line
			(start -0.15 0.4)
			(end 0.15 0.4)
			(stroke
				(width 0.15)
				(type solid)
			)
			(layer "B.SilkS")
		)
		(fp_rect
			(start -1.25 0.65)
			(end 1.25 -0.65)
			(stroke
				(width 0.05)
				(type solid)
			)
			(fill no)
			(layer "B.CrtYd")
		)
		(fp_line
			(start -0.803 -0.406)
			(end -0.803 0.408)
			(stroke
				(width 0.15)
				(type solid)
			)
			(layer "B.Fab")
		)
		(fp_line
			(start 0.8 -0.406)
			(end -0.803 -0.406)
			(stroke
				(width 0.15)
				(type solid)
			)
			(layer "B.Fab")
		)
		(fp_line
			(start 0.8 0.408)
			(end -0.803 0.408)
			(stroke
				(width 0.15)
				(type solid)
			)
			(layer "B.Fab")
		)
		(fp_line
			(start 0.8 0.408)
			(end 0.8 -0.406)
			(stroke
				(width 0.15)
				(type solid)
			)
			(layer "B.Fab")
		)
		(fp_text user "License: Apache-2.0"
			(at -1.653 -5.9 180)
			(layer "B.Fab")
			(effects
				(font
					(size 0.7 0.7)
					(thickness 0.15)
				)
				(justify left bottom mirror)
			)
		)
		(fp_text user "Author: Antmicro"
			(at -1.653 -3.162 180)
			(layer "B.Fab")
			(effects
				(font
					(size 0.7 0.7)
					(thickness 0.15)
				)
				(justify left bottom mirror)
			)
		)
		(fp_text user "${REFERENCE}"
			(at -1.653 -4.6 180)
			(layer "B.Fab")
			(effects
				(font
					(size 0.7 0.7)
					(thickness 0.15)
				)
				(justify left bottom mirror)
			)
		)
		(pad "1" smd roundrect
			(at -0.7 0)
			(size 0.8 1)
			(layers "B.Cu" "B.Mask" "B.Paste")
			(roundrect_rratio 0.2)
			(net 18 "+1V88")
			(pintype "passive")
		)
		(pad "2" smd roundrect
			(at 0.7 0)
			(size 0.8 1)
			(layers "B.Cu" "B.Mask" "B.Paste")
			(roundrect_rratio 0.2)
			(net 135 "+1V88_CT")
			(pintype "passive")
		)
	)
	(footprint "antmicro-footprints:C_0402_1005Metric"
		(layer "B.Cu")
		(at 151.381865 89.535116 -90)
		(descr "Capacitor SMD 0402")
		(tags "capacitor SMD 0402")
		(property "Reference" "C185"
			(at 10.264883 -18.868134 90)
			(layer "B.SilkS")
			(effects
				(font
					(size 0.7 0.7)
					(thickness 0.15)
				)
				(justify mirror)
			)
		)
		(property "Value" "C_1u_25V_0402"
			(at -1.022927 -2.155213 90)
			(layer "B.Fab")
			(effects
				(font
					(size 0.7 0.7)
					(thickness 0.15)
				)
				(justify left bottom mirror)
			)
		)
		(property "Datasheet" "https://www.murata.com/products/productdetail?partno=GRM155R61E105KE11%23"
			(at 0 0 90)
			(layer "B.Fab")
			(hide yes)
			(effects
				(font
					(size 1.27 1.27)
					(thickness 0.15)
				)
				(justify mirror)
			)
		)
		(property "Description" "SMD Multilayer Ceramic Capacitor, 1 µF, 25 V, 0402 [1005 Metric], ± 10%, X5R, GRM Series"
			(at 0 0 90)
			(layer "B.Fab")
			(hide yes)
			(effects
				(font
					(size 1.27 1.27)
					(thickness 0.15)
				)
				(justify mirror)
			)
		)
		(property "MPN" "GRM155R61E105KE11J"
			(at 0 0 270)
			(unlocked yes)
			(layer "B.Fab")
			(hide yes)
			(effects
				(font
					(size 1 1)
					(thickness 0.15)
				)
				(justify mirror)
			)
		)
		(property "Manufacturer" "Murata"
			(at 0 0 270)
			(unlocked yes)
			(layer "B.Fab")
			(hide yes)
			(effects
				(font
					(size 1 1)
					(thickness 0.15)
				)
				(justify mirror)
			)
		)
		(property "License" "Apache-2.0"
			(at 0 0 270)
			(unlocked yes)
			(layer "B.Fab")
			(hide yes)
			(effects
				(font
					(size 1 1)
					(thickness 0.15)
				)
				(justify mirror)
			)
		)
		(property "Author" "Antmicro"
			(at 0 0 270)
			(unlocked yes)
			(layer "B.Fab")
			(hide yes)
			(effects
				(font
					(size 1 1)
					(thickness 0.15)
				)
				(justify mirror)
			)
		)
		(property "Val" "1u"
			(at 0 0 270)
			(unlocked yes)
			(layer "B.Fab")
			(hide yes)
			(effects
				(font
					(size 1 1)
					(thickness 0.15)
				)
				(justify mirror)
			)
		)
		(property "Voltage" "25V"
			(at 0 0 270)
			(unlocked yes)
			(layer "B.Fab")
			(hide yes)
			(effects
				(font
					(size 1 1)
					(thickness 0.15)
				)
				(justify mirror)
			)
		)
		(property "Dielectric" "X5R"
			(at 0 0 270)
			(unlocked yes)
			(layer "B.Fab")
			(hide yes)
			(effects
				(font
					(size 1 1)
					(thickness 0.15)
				)
				(justify mirror)
			)
		)
		(sheetname "/X710-AT2 power/")
		(sheetfile "x710-at2-power.kicad_sch")
		(attr smd)
		(fp_rect
			(start -0.925 0.47)
			(end 0.925 -0.47)
			(stroke
				(width 0.05)
				(type default)
			)
			(fill no)
			(layer "B.CrtYd")
		)
		(fp_line
			(start -0.494 0.25)
			(end 0.504 0.25)
			(stroke
				(width 0.15)
				(type solid)
			)
			(layer "B.Fab")
		)
		(fp_line
			(start 0.504 0.25)
			(end 0.504 -0.248)
			(stroke
				(width 0.15)
				(type solid)
			)
			(layer "B.Fab")
		)
		(fp_line
			(start -0.494 -0.248)
			(end -0.494 0.25)
			(stroke
				(width 0.15)
				(type solid)
			)
			(layer "B.Fab")
		)
		(fp_line
			(start 0.504 -0.248)
			(end -0.494 -0.248)
			(stroke
				(width 0.15)
				(type solid)
			)
			(layer "B.Fab")
		)
		(fp_text user "Author: Antmicro"
			(at -0.939 -3.399 90)
			(layer "B.Fab")
			(effects
				(font
					(size 0.7 0.7)
					(thickness 0.15)
				)
				(justify left bottom mirror)
			)
		)
		(fp_text user "License: Apache-2.0"
			(at -0.939 -5.799 90)
			(layer "B.Fab")
			(effects
				(font
					(size 0.7 0.7)
					(thickness 0.15)
				)
				(justify left bottom mirror)
			)
		)
		(fp_text user "${REFERENCE}"
			(at -0.939 -4.599 90)
			(layer "B.Fab")
			(effects
				(font
					(size 0.7 0.7)
					(thickness 0.15)
				)
				(justify left bottom mirror)
			)
		)
		(pad "1" smd roundrect
			(at -0.48 0 270)
			(size 0.59 0.64)
			(layers "B.Cu" "B.Mask" "B.Paste")
			(roundrect_rratio 0.25)
			(net 23 "GND")
			(pintype "passive")
		)
		(pad "2" smd roundrect
			(at 0.48 0 270)
			(size 0.59 0.64)
			(layers "B.Cu" "B.Mask" "B.Paste")
			(roundrect_rratio 0.25)
			(net 18 "+1V88")
			(pintype "passive")
		)
	)
	(footprint "antmicro-footprints:C_0402_1005Metric"
		(layer "B.Cu")
		(at 120.3 150.6)
		(descr "Capacitor SMD 0402")
		(tags "capacitor SMD 0402")
		(property "Reference" "C3"
			(at 0.7 1.65 180)
			(layer "B.SilkS")
			(effects
				(font
					(size 0.7 0.7)
					(thickness 0.15)
				)
				(justify left bottom mirror)
			)
		)
		(property "Value" "C_100n_0402"
			(at -1.022927 -2.155213 180)
			(layer "B.Fab")
			(effects
				(font
					(size 0.7 0.7)
					(thickness 0.15)
				)
				(justify left bottom mirror)
			)
		)
		(property "Datasheet" "https://www.murata.com/products/productdetail?partno=GRM155R61H104KE14%23"
			(at 0 0 180)
			(layer "B.Fab")
			(hide yes)
			(effects
				(font
					(size 1.27 1.27)
					(thickness 0.15)
				)
				(justify mirror)
			)
		)
		(property "Description" "SMD Multilayer Ceramic Capacitor, 0.1 µF, 50 V, 0402 [1005 Metric], ± 10%, X5R, GRM Series"
			(at 0 0 180)
			(layer "B.Fab")
			(hide yes)
			(effects
				(font
					(size 1.27 1.27)
					(thickness 0.15)
				)
				(justify mirror)
			)
		)
		(property "MPN" "GRM155R61H104KE14D"
			(at 0 0 0)
			(unlocked yes)
			(layer "B.Fab")
			(hide yes)
			(effects
				(font
					(size 1 1)
					(thickness 0.15)
				)
				(justify mirror)
			)
		)
		(property "Manufacturer" "Murata"
			(at 0 0 0)
			(unlocked yes)
			(layer "B.Fab")
			(hide yes)
			(effects
				(font
					(size 1 1)
					(thickness 0.15)
				)
				(justify mirror)
			)
		)
		(property "License" "Apache-2.0"
			(at 0 0 0)
			(unlocked yes)
			(layer "B.Fab")
			(hide yes)
			(effects
				(font
					(size 1 1)
					(thickness 0.15)
				)
				(justify mirror)
			)
		)
		(property "Val" "100n"
			(at 0 0 0)
			(unlocked yes)
			(layer "B.Fab")
			(hide yes)
			(effects
				(font
					(size 1 1)
					(thickness 0.15)
				)
				(justify mirror)
			)
		)
		(property "Voltage" "50V"
			(at 0 0 0)
			(unlocked yes)
			(layer "B.Fab")
			(hide yes)
			(effects
				(font
					(size 1 1)
					(thickness 0.15)
				)
				(justify mirror)
			)
		)
		(property "Dielectric" "X5R"
			(at 0 0 0)
			(unlocked yes)
			(layer "B.Fab")
			(hide yes)
			(effects
				(font
					(size 1 1)
					(thickness 0.15)
				)
				(justify mirror)
			)
		)
		(property "Author" "Antmicro"
			(at 0 0 0)
			(unlocked yes)
			(layer "B.Fab")
			(hide yes)
			(effects
				(font
					(size 1 1)
					(thickness 0.15)
				)
				(justify mirror)
			)
		)
		(sheetname "/USB-C connector/")
		(sheetfile "USB-C_connector.kicad_sch")
		(attr smd)
		(fp_rect
			(start -0.925 0.47)
			(end 0.925 -0.47)
			(stroke
				(width 0.05)
				(type default)
			)
			(fill no)
			(layer "B.CrtYd")
		)
		(fp_line
			(start -0.494 -0.248)
			(end -0.494 0.25)
			(stroke
				(width 0.15)
				(type solid)
			)
			(layer "B.Fab")
		)
		(fp_line
			(start -0.494 0.25)
			(end 0.504 0.25)
			(stroke
				(width 0.15)
				(type solid)
			)
			(layer "B.Fab")
		)
		(fp_line
			(start 0.504 -0.248)
			(end -0.494 -0.248)
			(stroke
				(width 0.15)
				(type solid)
			)
			(layer "B.Fab")
		)
		(fp_line
			(start 0.504 0.25)
			(end 0.504 -0.248)
			(stroke
				(width 0.15)
				(type solid)
			)
			(layer "B.Fab")
		)
		(fp_text user "Author: Antmicro"
			(at -0.939 -3.399 180)
			(layer "B.Fab")
			(effects
				(font
					(size 0.7 0.7)
					(thickness 0.15)
				)
				(justify left bottom mirror)
			)
		)
		(fp_text user "${REFERENCE}"
			(at -0.939 -4.599 180)
			(layer "B.Fab")
			(effects
				(font
					(size 0.7 0.7)
					(thickness 0.15)
				)
				(justify left bottom mirror)
			)
		)
		(fp_text user "License: Apache-2.0"
			(at -0.939 -5.799 180)
			(layer "B.Fab")
			(effects
				(font
					(size 0.7 0.7)
					(thickness 0.15)
				)
				(justify left bottom mirror)
			)
		)
		(pad "1" smd roundrect
			(at -0.48 0)
			(size 0.59 0.64)
			(layers "B.Cu" "B.Mask" "B.Paste")
			(roundrect_rratio 0.25)
			(net 23 "GND")
			(pintype "passive")
		)
		(pad "2" smd roundrect
			(at 0.48 0)
			(size 0.59 0.64)
			(layers "B.Cu" "B.Mask" "B.Paste")
			(roundrect_rratio 0.25)
			(net 215 "/USB-C connector/VBUS")
			(pintype "passive")
		)
	)
)
